#ISCELL
  pure_quanta quanta_title_block_c *
  *
#ISCELL
  standard offpage *
  page34_i1
#ISCELL
  standard offpage *
  page34_i104
#ISCELL
  standard offpage *
  page34_i105
#CELL
  pure_quanta q_res *
  page34_i106
#CELL
  pure_quanta q_res *
  page34_i107
#ISCELL
  pure_quanta_power universal_power *
  page34_i108
#ISCELL
  standard offpage *
  page34_i109
#ISCELL
  standard offpage *
  page34_i110
#CELL
  pure_quanta q_res *
  page34_i111
#CELL
  pure_quanta q_res *
  page34_i112
#CELL
  pure_quanta pca9617adp *
  page34_i18
#ISCELL
  standard offpage *
  page34_i2
#ISCELL
  standard offpage *
  page34_i26
#ISCELL
  standard offpage *
  page34_i27
#ISCELL
  pure_quanta_power universal_gnd *
  page34_i28
#CELL
  pure_quanta q_cap *
  page34_i29
#ISCELL
  pure_quanta_power universal_power *
  page34_i3
#ISCELL
  pure_quanta_power universal_power *
  page34_i31
#CELL
  pure_quanta sn74lvc2g07dckr *
  page34_i32
#ISCELL
  pure_quanta_power universal_gnd *
  page34_i33
#ISCELL
  standard offpage *
  page34_i34
#ISCELL
  standard offpage *
  page34_i35
#CELL
  pure_quanta q_res *
  page34_i4
#ISCELL
  pure_quanta_power universal_gnd *
  page34_i40
#ISCELL
  standard offpage *
  page34_i41
#ISCELL
  standard offpage *
  page34_i42
#ISCELL
  pure_quanta_power universal_power *
  page34_i43
#CELL
  pure_quanta q_cap *
  page34_i44
#ISCELL
  pure_quanta_power universal_gnd *
  page34_i45
#ISCELL
  pure_quanta_power universal_power *
  page34_i46
#CELL
  pure_quanta q_cap *
  page34_i47
#ISCELL
  pure_quanta_power universal_gnd *
  page34_i48
#CELL
  pure_quanta q_res *
  page34_i5
#ISCELL
  standard offpage *
  page34_i50
#ISCELL
  standard offpage *
  page34_i51
#ISCELL
  standard offpage *
  page34_i52
#CELL
  pure_quanta q_res *
  page34_i53
#ISCELL
  pure_quanta_power universal_power *
  page34_i54
#CELL
  pure_quanta sn74lvc1g07dbvr *
  page34_i55
#ISCELL
  pure_quanta_power universal_gnd *
  page34_i56
#ISCELL
  pure_quanta_power universal_gnd *
  page34_i58
#CELL
  pure_quanta q_cap *
  page34_i59
#CELL
  pure_quanta q_res *
  page34_i60
#ISCELL
  standard offpage *
  page34_i61
#ISCELL
  pure_quanta_power p1v0 *
  page34_i62
